G04 ================== begin FILE IDENTIFICATION RECORD ==================*
G04 Layout Name:  D:/<user>/Wistron_project/16317-1/gbr/16317-1.brd*
G04 Film Name:    P_OUTLINE*
G04 File Format:  Gerber RS274X*
G04 File Origin:  Cadence Allegro 16.5-S056*
G04 Origin Date:  Fri Jun 09 15:52:25 2017*
G04 *
G04 Layer:  BOARD GEOMETRY/PANEL_OUTLINE*
G04 *
G04 Offset:    (0.00 0.00)*
G04 Mirror:    No*
G04 Mode:      Positive*
G04 Rotation:  0*
G04 FullContactRelief:  No*
G04 UndefLineWidth:     6.00*
G04 ================== end FILE IDENTIFICATION RECORD ====================*
%FSLAX35Y35*MOIN*%
%IR0*IPPOS*OFA0.00000B0.00000*MIA0B0*SFA1.00000B1.00000*%
%ADD10C,.006*%
G75*
%LPD*%
G75*
G54D10*
G01X0Y3937D02*
G03X3937Y0I3937J0D01*
G01X0Y3937D02*
G03X3937Y0I3937J0D01*
G01D02*
X779528D01*
G01X3937D02*
X779528D01*
G01X0Y1456693D02*
Y3937D01*
G01Y1456693D02*
Y3937D01*
G01X7874Y1460630D02*
X3937D01*
G01D02*
X7874D01*
G01X3937D02*
G03X0Y1456693I0J-3937D01*
G01X3937Y1460630D02*
G03X0Y1456693I0J-3937D01*
G01X101378Y1519685D02*
G03X97441Y1515748I0J-3937D01*
G01X101378Y1519685D02*
G03X97441Y1515748I0J-3937D01*
G01D02*
Y1509055D01*
G01Y1515748D02*
Y1509055D01*
G01X93504Y1505118D02*
X67913D01*
G01X93504D02*
G03X97441Y1509055I0J3937D01*
G01X93504Y1505118D02*
G03X97441Y1509055I0J3937D01*
G01X67913Y1505118D02*
X93504D01*
G01X63976Y1515748D02*
G03X60039Y1519685I-3937J0D01*
G01X63976Y1515748D02*
G03X60039Y1519685I-3937J0D01*
G01X63976Y1509055D02*
Y1515748D01*
G01Y1509055D02*
G03X67913Y1505118I3937J0D01*
G01X63976Y1509055D02*
G03X67913Y1505118I3937J0D01*
G01X63976Y1515748D02*
Y1509055D01*
G01X7874Y1460630D02*
G03X11811Y1464567I0J3937D01*
G01X7874Y1460630D02*
G03X11811Y1464567I0J3937D01*
G01X15748Y1519685D02*
G03X11811Y1515748I0J-3937D01*
G01X15748Y1519685D02*
G03X11811Y1515748I0J-3937D01*
G01D02*
Y1464567D01*
G01Y1515748D02*
Y1464567D01*
G01X60039Y1519685D02*
X15748D01*
G01X60039D02*
X15748D01*
G01X141181Y277843D02*
G03X148106Y264712I37662J11471D01*
G01X141181Y277843D02*
G03X148106Y264712I37662J11471D01*
G01X141181Y277843D02*
G03X121220I-9980J-3040D01*
G01X114295Y264712D02*
G03X121220Y277843I-30737J24602D01*
G01X141181D02*
G03X121220I-9980J-3040D01*
G01X114295Y264712D02*
G03X121220Y277843I-30737J24601D01*
G01X114295Y264712D02*
G03X148106I16905J-13531D01*
G01X114295D02*
G03X148106I16905J-13531D01*
G01X141181Y730599D02*
G03X148106Y717468I37662J11471D01*
G01X141181Y730599D02*
G03X148106Y717468I37662J11471D01*
G01X141181Y730599D02*
G03X121220I-9980J-3040D01*
G01X114295Y717468D02*
G03X121220Y730599I-30737J24601D01*
G01X141181D02*
G03X121220I-9980J-3040D01*
G01X114295Y717468D02*
G03X121220Y730599I-30737J24601D01*
G01X114295Y717468D02*
G03X148106I16905J-13531D01*
G01X114295D02*
G03X148106I16905J-13531D01*
G01X114295Y1170224D02*
G03X148106I16905J-13531D01*
G01X114295D02*
G03X148106I16905J-13531D01*
G01X141181Y1183355D02*
G03X148106Y1170224I37662J11471D01*
G01X141181Y1183355D02*
G03X148106Y1170224I37662J11471D01*
G01X141181Y1183355D02*
G03X121220I-9980J-3040D01*
G01X141181D02*
G03X121220I-9980J-3040D01*
G01X114295Y1170224D02*
G03X121220Y1183355I-30737J24602D01*
G01X114295Y1170224D02*
G03X121220Y1183355I-30737J24601D01*
G01X280709Y1519685D02*
X101378D01*
G01X280709D02*
X101378D01*
G01X284646Y1515748D02*
G03X280709Y1519685I-3937J0D01*
G01X284646Y1515748D02*
G03X280709Y1519685I-3937J0D01*
G01X284646Y1500000D02*
Y1515748D01*
G01Y1500000D02*
G03X288583Y1496063I3937J0D01*
G01X493307D02*
X288583D01*
G01X284646Y1500000D02*
G03X288583Y1496063I3937J0D01*
G01X493307D02*
X288583D01*
G01X284646Y1515748D02*
Y1500000D01*
G01X389213Y277843D02*
G03X369252I-9981J-3040D01*
G01X389213D02*
G03X369252I-9981J-3040D01*
G01X362327Y264712D02*
G03X369252Y277843I-30737J24602D01*
G01X362327Y264712D02*
G03X369252Y277843I-30737J24602D01*
G01X362327Y264712D02*
G03X396138I16905J-13531D01*
G01X362327D02*
G03X396138I16905J-13531D01*
G01X389213Y730599D02*
G03X369252I-9981J-3040D01*
G01X389213D02*
G03X369252I-9981J-3040D01*
G01X362327Y717468D02*
G03X369252Y730599I-30737J24602D01*
G01X362327Y717468D02*
G03X369252Y730599I-30737J24602D01*
G01X362327Y717468D02*
G03X396138I16905J-13531D01*
G01X362327D02*
G03X396138I16905J-13531D01*
G01X362327Y1170224D02*
G03X396138I16905J-13531D01*
G01X362327D02*
G03X396138I16905J-13531D01*
G01X389213Y1183355D02*
G03X369252I-9981J-3040D01*
G01X389213D02*
G03X369252I-9981J-3040D01*
G01X362327Y1170224D02*
G03X369252Y1183355I-30737J24602D01*
G01X362327Y1170224D02*
G03X369252Y1183355I-30737J24602D01*
G01X322441Y1503937D02*
G03Y1496063I0J-3937D01*
G01X459449Y1503937D02*
X322441D01*
G01X459449D02*
X322441D01*
G01D02*
G03Y1496063I0J-3937D01*
G01X296457Y1519685D02*
G03X292520Y1515748I0J-3937D01*
G01X296457Y1519685D02*
X485433D01*
G01X296457D02*
G03X292520Y1515748I0J-3937D01*
G01X296457Y1519685D02*
X485433D01*
G01X304331Y1503937D02*
X292520D01*
G01Y1515748D02*
Y1503937D01*
G01X304331D02*
X292520D01*
G01Y1515748D02*
Y1503937D01*
G01X304331Y1496063D02*
G03Y1503937I0J3937D01*
G01Y1496063D02*
G03Y1503937I0J3937D01*
G01X389213Y277843D02*
G03X396138Y264712I37662J11471D01*
G01X389213Y277843D02*
G03X396138Y264712I37662J11470D01*
G01X389213Y730599D02*
G03X396138Y717468I37662J11471D01*
G01X389213Y730599D02*
G03X396138Y717468I37662J11470D01*
G01X389213Y1183355D02*
G03X396138Y1170224I37662J11471D01*
G01X389213Y1183355D02*
G03X396138Y1170224I37662J11470D01*
G01X477559Y1503937D02*
G03Y1496063I0J-3937D01*
G01X459449D02*
G03Y1503937I0J3937D01*
G01X489370D02*
X477559D01*
G01D02*
G03Y1496063I0J-3937D01*
G01X459449D02*
G03Y1503937I0J3937D01*
G01X489370D02*
X477559D01*
G01X489370Y1515748D02*
G03X485433Y1519685I-3937J0D01*
G01X489370Y1515748D02*
G03X485433Y1519685I-3937J0D01*
G01X501181D02*
G03X497244Y1515748I0J-3937D01*
G01X680512Y1519685D02*
X501181D01*
G01D02*
G03X497244Y1515748I0J-3937D01*
G01X680512Y1519685D02*
X501181D01*
G01X489370Y1515748D02*
Y1503937D01*
G01X493307Y1496063D02*
G03X497244Y1500000I0J3937D01*
G01Y1515748D02*
Y1500000D01*
G01X489370Y1515748D02*
Y1503937D01*
G01X493307Y1496063D02*
G03X497244Y1500000I0J3937D01*
G01Y1515748D02*
Y1500000D01*
G01X637244Y277843D02*
G03X644169Y264712I37662J11471D01*
G01X637244Y277843D02*
G03X644169Y264712I37662J11471D01*
G01X637244Y277843D02*
G03X617283I-9980J-3040D01*
G01X610358Y264712D02*
G03X617283Y277843I-30737J24602D01*
G01X637244D02*
G03X617283I-9980J-3040D01*
G01X610358Y264712D02*
G03X617283Y277843I-30737J24601D01*
G01X610358Y264712D02*
G03X644169I16906J-13531D01*
G01X610358D02*
G03X644169I16906J-13531D01*
G01X637244Y730599D02*
G03X644169Y717468I37662J11471D01*
G01X637244Y730599D02*
G03X644169Y717468I37662J11471D01*
G01X637244Y730599D02*
G03X617283I-9980J-3040D01*
G01X610358Y717468D02*
G03X617283Y730599I-30737J24601D01*
G01X637244D02*
G03X617283I-9980J-3040D01*
G01X610358Y717468D02*
G03X617283Y730599I-30737J24601D01*
G01X610358Y717468D02*
G03X644169I16906J-13531D01*
G01X610358D02*
G03X644169I16906J-13531D01*
G01X610358Y1170224D02*
G03X644169I16906J-13531D01*
G01X610358D02*
G03X644169I16906J-13531D01*
G01X637244Y1183355D02*
G03X644169Y1170224I37662J11471D01*
G01X637244Y1183355D02*
G03X644169Y1170224I37662J11471D01*
G01X637244Y1183355D02*
G03X617283I-9980J-3040D01*
G01X637244D02*
G03X617283I-9980J-3040D01*
G01X610358Y1170224D02*
G03X617283Y1183355I-30737J24602D01*
G01X610358Y1170224D02*
G03X617283Y1183355I-30737J24601D01*
G01X730339Y383610D02*
G03X764149I16905J-13531D01*
G01X730339Y383609D02*
G03X764150I16905J-13530D01*
G01X757225Y396741D02*
G03X764149Y383610I37663J11469D01*
G01X757224Y396741D02*
G03X764150Y383609I37662J11471D01*
G01X757225Y396741D02*
G03X737264I-9981J-3040D01*
G01X730339Y383610D02*
G03X737264Y396741I-30737J24602D01*
G01X757224D02*
G03X737264I-9980J-3041D01*
G01X730339Y383609D02*
G03X737264Y396741I-30738J24601D01*
G01X757225Y829811D02*
G03X764149Y816680I37663J11469D01*
G01X757224Y829811D02*
G03X764150Y816680I37662J11473D01*
G01X757225Y829811D02*
G03X737264I-9981J-3039D01*
G01X757224D02*
G03X737264I-9980J-3040D01*
G01X730339Y816680D02*
G03X737264Y829811I-30737J24602D01*
G01X730339Y816680D02*
G03X737264Y829811I-30737J24602D01*
G01X730339Y816680D02*
G03X764149I16905J-13531D01*
G01X730339D02*
G03X764150I16905J-13531D01*
G01X721850Y1519685D02*
G03X717913Y1515748I0J-3937D01*
G01X775591Y1519685D02*
X721850D01*
G01D02*
G03X717913Y1515748I0J-3937D01*
G01X775591Y1519685D02*
X721850D01*
G01X713976Y1505118D02*
G03X717913Y1509055I0J3937D01*
G01Y1515748D02*
Y1509055D01*
G01X713976Y1505118D02*
G03X717913Y1509055I0J3937D01*
G01Y1515748D02*
Y1509055D01*
G01X684449Y1515748D02*
G03X680512Y1519685I-3937J0D01*
G01X684449Y1515748D02*
G03X680512Y1519685I-3937J0D01*
G01X684449Y1509055D02*
Y1515748D01*
G01Y1509055D02*
G03X688386Y1505118I3937J0D01*
G01X713976D02*
X688386D01*
G01X684449Y1509055D02*
G03X688386Y1505118I3937J0D01*
G01D02*
X713976D01*
G01X684449Y1515748D02*
Y1509055D01*
G01X791339Y3937D02*
G03X795276Y0I3937J0D01*
G01D02*
X892317D01*
G01X791339Y3937D02*
Y23622D01*
G01Y3937D02*
G03X795276Y0I3937J0D01*
G01X791339Y3937D02*
Y23622D01*
G01X795276Y0D02*
X892317D01*
G01X783465Y54331D02*
G03X791339I3937J0D01*
G01X783465D02*
G03X791339I3937J0D01*
G01Y23622D02*
G03X783465I-3937J0D01*
G01X791339D02*
G03X783465I-3937J0D01*
G01X779528Y0D02*
G03X783465Y3937I0J3937D01*
G01X779528Y0D02*
G03X783465Y3937I0J3937D01*
G01X791339Y54331D02*
Y181890D01*
G01Y54331D02*
Y181890D01*
G01X783465Y3937D02*
Y185827D01*
G01Y3937D02*
Y185827D01*
G01X811024Y181890D02*
G03X822835Y193701I0J11811D01*
G01X791339Y181890D02*
X811024D01*
G01D02*
G03X822835Y193701I0J11811D01*
G01X791339Y181890D02*
X811024D01*
G01X787402Y189764D02*
G03X783465Y185827I0J-3937D01*
G01X787402Y189764D02*
G03X783465Y185827I0J-3937D01*
G01X811024Y189764D02*
G03X814961Y193701I0J3937D01*
G01X787402Y189764D02*
X811024D01*
G01D02*
G03X814961Y193701I0J3937D01*
G01X787402Y189764D02*
X811024D01*
G01X822835Y193701D02*
Y240157D01*
G01Y193701D02*
Y240157D01*
G01X814961Y193701D02*
Y244094D01*
G01Y193701D02*
Y244094D01*
G01X818898Y248031D02*
G03X814961Y244094I0J-3937D01*
G01X818898Y248031D02*
G03X814961Y244094I0J-3937D01*
G01X928098Y240157D02*
X822835D01*
G01X928098D02*
X822835D01*
G01X818898Y248031D02*
X1055118D01*
G01D02*
X818898D01*
G01X954331Y1503937D02*
X817323D01*
G01X954331D02*
X817323D01*
G01X791339Y1519685D02*
G03X787402Y1515748I0J-3937D01*
G01X791339Y1519685D02*
X980315D01*
G01X791339D02*
G03X787402Y1515748I0J-3937D01*
G01X791339Y1519685D02*
X980315D01*
G01X817323Y1503937D02*
G03Y1496063I0J-3937D01*
G01X799213D02*
G03Y1503937I0J3937D01*
G01D02*
X787402D01*
G01Y1515748D02*
Y1503937D01*
G01X799213D02*
X787402D01*
G01X817323D02*
G03Y1496063I0J-3937D01*
G01X799213D02*
G03Y1503937I0J3937D01*
G01X787402Y1515748D02*
Y1503937D01*
G01X779528Y1515748D02*
G03X775591Y1519685I-3937J0D01*
G01X779528Y1515748D02*
G03X775591Y1519685I-3937J0D01*
G01X779528Y1500000D02*
Y1515748D01*
G01Y1500000D02*
G03X783465Y1496063I3937J0D01*
G01X988189D02*
X783465D01*
G01X779528Y1500000D02*
G03X783465Y1496063I3937J0D01*
G01X988189D02*
X783465D01*
G01X779528Y1515748D02*
Y1500000D01*
G01X900191Y0D02*
G03X892317I-3937J0D01*
G01X896254D02*
Y-394D01*
G01Y0D02*
Y394D01*
G01X895762Y0D02*
X896746D01*
G01X900191D02*
G03X892317I-3937J0D01*
G01X900191D02*
X1212598D01*
G01X900191D02*
X1212598D01*
G01X953294Y248031D02*
G03Y240157I1J-3937D01*
G01X1051181D02*
X953294D01*
G01Y248031D02*
G03Y240157I1J-3937D01*
G01X928098D02*
G03Y248031I0J3937D01*
G01Y240157D02*
G03Y248031I0J3937D01*
G01X1051181Y240157D02*
X953294D01*
G01X971398Y718788D02*
G03X951437I-9980J-3040D01*
G01X944512Y705657D02*
G03X951437Y718788I-30737J24602D01*
G01X971398D02*
G03X951437I-9980J-3040D01*
G01X944512Y705657D02*
G03X951437Y718788I-30737J24602D01*
G01X944512Y705657D02*
G03X978323I16905J-13531D01*
G01X944512D02*
G03X978323I16905J-13531D01*
G01X944512Y974161D02*
G03X978323I16905J-13531D01*
G01X944512D02*
G03X978323I16905J-13531D01*
G01X971398Y987292D02*
G03X951437I-9980J-3040D01*
G01X944512Y974161D02*
G03X951437Y987292I-30737J24602D01*
G01X971398D02*
G03X951437I-9980J-3040D01*
G01X944512Y974161D02*
G03X951437Y987292I-30737J24602D01*
G01X954331Y1496063D02*
G03Y1503937I0J3937D01*
G01Y1496063D02*
G03Y1503937I0J3937D01*
G01X1051181Y193701D02*
G03X1062992Y181890I11811J0D01*
G01X1051181Y193701D02*
G03X1062992Y181890I11811J0D01*
G01X1051181Y240157D02*
Y193701D01*
G01Y240157D02*
Y193701D01*
G01X971398Y718788D02*
G03X978323Y705657I37662J11471D01*
G01X971398Y718788D02*
G03X978323Y705657I37662J11470D01*
G01X971398Y987292D02*
G03X978323Y974161I37662J11471D01*
G01X971398Y987292D02*
G03X978323Y974161I37662J11470D01*
G01X1059196Y1519685D02*
X996063D01*
G01X1059196D02*
X996063D01*
G01X984252Y1515748D02*
G03X980315Y1519685I-3937J0D01*
G01X984252Y1515748D02*
G03X980315Y1519685I-3937J0D01*
G01X996063D02*
G03X992126Y1515748I0J-3937D01*
G01X996063Y1519685D02*
G03X992126Y1515748I0J-3937D01*
G01X972441Y1503937D02*
G03Y1496063I0J-3937D01*
G01X984252Y1503937D02*
X972441D01*
G01X984252Y1515748D02*
Y1503937D01*
G01X972441D02*
G03Y1496063I0J-3937D01*
G01X988189D02*
G03X992126Y1500000I0J3937D01*
G01Y1515748D02*
Y1500000D01*
G01X984252Y1515748D02*
Y1503937D01*
G01D02*
X972441D01*
G01X988189Y1496063D02*
G03X992126Y1500000I0J3937D01*
G01Y1515748D02*
Y1500000D01*
G01X1133071Y189764D02*
G03Y181890I0J-3937D01*
G01D02*
X1216535D01*
G01X1133071D02*
X1216535D01*
G01X1133071Y189764D02*
G03Y181890I0J-3937D01*
G01X1102362D02*
G03Y189764I0J3937D01*
G01Y181890D02*
G03Y189764I0J3937D01*
G01X1062992Y181890D02*
X1102362D01*
G01X1062992D02*
X1102362D01*
G01X1059055Y244094D02*
G03X1055118Y248031I-3937J0D01*
G01X1059055Y244094D02*
G03X1055118Y248031I-3937J0D01*
G01X1059055Y244094D02*
Y193701D01*
G01Y244094D02*
Y193701D01*
G01X1062992Y189764D02*
X1220472D01*
G01X1059055Y193701D02*
G03X1062992Y189764I3937J0D01*
G01X1059055Y193701D02*
G03X1062992Y189764I3937J0D01*
G01D02*
X1220472D01*
G01X1085630Y1417323D02*
G03X1089567Y1421260I0J3937D01*
G01X1085630Y1417323D02*
G03X1089567Y1421260I0J3937D01*
G01X1072638D02*
G03X1076575Y1417322I3937J-1D01*
G01X1085630Y1417323D02*
X1076575D01*
G01X1072638Y1421260D02*
G03X1076575Y1417323I3937J0D01*
G01D02*
X1085630D01*
G01X1089567Y1506243D02*
Y1421260D01*
G01Y1506243D02*
Y1421260D01*
G01X1072638D02*
Y1506243D01*
G01D02*
Y1421260D01*
G01X1103009Y1519685D02*
G03X1100225Y1518532I0J-3937D01*
G01X1207283Y1519685D02*
X1103009D01*
G01D02*
G03X1100225Y1518532I0J-3937D01*
G01X1207283Y1519685D02*
X1103009D01*
G01X1090720Y1509027D02*
G03X1089567Y1506243I2784J-2784D01*
G01X1100225Y1518532D02*
X1090720Y1509027D01*
G01D02*
G03X1089567Y1506243I2784J-2784D01*
G01X1100225Y1518532D02*
X1090720Y1509027D01*
G01X1061980Y1518532D02*
G03X1059196Y1519685I-2784J-2784D01*
G01X1061980Y1518532D02*
G03X1059196Y1519685I-2784J-2784D01*
G01X1071485Y1509027D02*
X1061980Y1518532D01*
G01X1072638Y1506243D02*
G03X1071485Y1509027I-3937J0D01*
G01X1072638Y1506243D02*
G03X1071485Y1509027I-3937J0D01*
G01X1061980Y1518532D02*
X1071485Y1509027D01*
G01X1216535Y54331D02*
G03X1224409I3937J0D01*
G01X1216535D02*
Y181890D01*
G01Y54331D02*
Y181890D01*
G01Y54331D02*
G03X1224409I3937J0D01*
G01Y23622D02*
G03X1216535I-3937J0D01*
G01X1224409D02*
G03X1216535I-3937J0D01*
G01X1212598Y0D02*
G03X1216535Y3937I0J3937D01*
G01D02*
Y23622D01*
G01X1212598Y0D02*
G03X1216535Y3937I0J3937D01*
G01X1224409D02*
G03X1228346Y0I3937J0D01*
G01X1224409Y185827D02*
Y3937D01*
G01X1216535D02*
Y23622D01*
G01X1224409Y3937D02*
G03X1228346Y0I3937J0D01*
G01X1224409Y3937D02*
Y185827D01*
G01X1228346Y0D02*
X1930906D01*
G01X1228346D02*
X1930906D01*
G01X1224409Y185827D02*
G03X1220472Y189764I-3937J0D01*
G01X1224409Y185827D02*
G03X1220472Y189764I-3937J0D01*
G01X1164984Y383609D02*
G03X1198795I16906J-13530D01*
G01X1164984D02*
G03X1198795I16906J-13530D01*
G01X1191870Y396741D02*
G03X1198795Y383610I37662J11471D01*
G01X1191870Y396741D02*
G03X1198795Y383609I37663J11469D01*
G01X1191870Y396741D02*
G03X1171909I-9980J-3040D01*
G01X1164984Y383610D02*
G03X1171909Y396741I-30737J24602D01*
G01X1191870D02*
G03X1171909I-9980J-3040D01*
G01X1164984Y383609D02*
G03X1171909Y396741I-30737J24601D01*
G01X1164984Y974161D02*
G03X1198795I16906J-13531D01*
G01X1164984D02*
G03X1198795I16906J-13531D01*
G01X1191870Y987292D02*
G03X1198795Y974161I37662J11471D01*
G01X1191870Y987292D02*
G03X1198795Y974161I37662J11471D01*
G01X1191870Y987292D02*
G03X1171909I-9980J-3040D01*
G01X1164984Y974161D02*
G03X1171909Y987292I-30737J24602D01*
G01X1191870D02*
G03X1171909I-9980J-3040D01*
G01X1164984Y974161D02*
G03X1171909Y987292I-30737J24601D01*
G01X1240748Y1505118D02*
G03X1244685Y1509055I0J3937D01*
G01X1240748Y1505118D02*
G03X1244685Y1509055I0J3937D01*
G01X1211220Y1515748D02*
G03X1207283Y1519685I-3937J0D01*
G01X1211220Y1515748D02*
G03X1207283Y1519685I-3937J0D01*
G01X1211220Y1509055D02*
Y1515748D01*
G01Y1509055D02*
G03X1215157Y1505118I3937J0D01*
G01X1240748D02*
X1215157D01*
G01X1211220Y1509055D02*
G03X1215157Y1505118I3937J0D01*
G01D02*
X1240748D01*
G01X1211220Y1515748D02*
Y1509055D01*
G01X1311851Y277843D02*
G03X1318775Y264712I37663J11469D01*
G01X1311850Y277843D02*
G03X1318776Y264712I37661J11473D01*
G01X1311851Y277843D02*
G03X1291890I-9980J-3040D01*
G01X1284965Y264712D02*
G03X1291890Y277843I-30737J24602D01*
G01X1311850D02*
G03X1291890I-9980J-3040D01*
G01X1284965Y264712D02*
G03X1291890Y277843I-30737J24602D01*
G01X1284965Y264712D02*
G03X1318775I16905J-13531D01*
G01X1284965D02*
G03X1318776I16906J-13531D01*
G01X1311851Y730599D02*
G03X1318775Y717468I37663J11469D01*
G01X1311850Y730599D02*
G03X1318776Y717468I37661J11473D01*
G01X1311851Y730599D02*
G03X1291890I-9980J-3040D01*
G01X1284965Y717468D02*
G03X1291891Y730599I-30736J24604D01*
G01X1311850D02*
G03X1291890I-9980J-3040D01*
G01X1284965Y717468D02*
G03X1291890Y730599I-30737J24602D01*
G01X1284965Y717468D02*
G03X1318775I16905J-13531D01*
G01X1284965D02*
G03X1318776I16906J-13531D01*
G01X1284965Y1170224D02*
G03X1318775I16905J-13531D01*
G01X1284965D02*
G03X1318776I16906J-13531D01*
G01X1311851Y1183355D02*
G03X1318775Y1170224I37663J11469D01*
G01X1311850Y1183355D02*
G03X1318776Y1170224I37661J11473D01*
G01X1311851Y1183355D02*
G03X1291890I-9980J-3040D01*
G01X1311850D02*
G03X1291890I-9980J-3040D01*
G01X1284965Y1170224D02*
G03X1291890Y1183355I-30737J24602D01*
G01X1284965Y1170224D02*
G03X1291890Y1183355I-30737J24602D01*
G01X1248622Y1519685D02*
G03X1244685Y1515748I0J-3937D01*
G01X1427953Y1519685D02*
X1248622D01*
G01D02*
G03X1244685Y1515748I0J-3937D01*
G01X1427953Y1519685D02*
X1248622D01*
G01X1244685Y1515748D02*
Y1509055D01*
G01Y1515748D02*
Y1509055D01*
G01X1431890Y1515748D02*
G03X1427953Y1519685I-3937J0D01*
G01X1431890Y1515748D02*
G03X1427953Y1519685I-3937J0D01*
G01X1431890Y1500000D02*
Y1515748D01*
G01Y1500000D02*
G03X1435827Y1496063I3937J0D01*
G01X1431890Y1500000D02*
G03X1435827Y1496063I3937J0D01*
G01X1431890Y1515748D02*
Y1500000D01*
G01X1532996Y264712D02*
G03X1566807I16906J-13531D01*
G01X1532996D02*
G03X1566807I16906J-13531D01*
G01X1532996Y717468D02*
G03X1566807I16906J-13531D01*
G01X1532996D02*
G03X1566807I16906J-13531D01*
G01X1532996Y1170224D02*
G03X1566807I16906J-13531D01*
G01X1532996D02*
G03X1566807I16906J-13531D01*
G01X1469685Y1503937D02*
G03Y1496063I0J-3937D01*
G01X1451575D02*
G03Y1503937I0J3937D01*
G01X1606693D02*
X1469685D01*
G01X1606693D02*
X1469685D01*
G01D02*
G03Y1496063I0J-3937D01*
G01X1451575D02*
G03Y1503937I0J3937D01*
G01X1443701Y1519685D02*
G03X1439764Y1515748I0J-3937D01*
G01X1443701Y1519685D02*
X1632677D01*
G01X1443701D02*
G03X1439764Y1515748I0J-3937D01*
G01X1443701Y1519685D02*
X1632677D01*
G01X1451575Y1503937D02*
X1439764D01*
G01Y1515748D02*
Y1503937D01*
G01X1451575D02*
X1439764D01*
G01X1640551Y1496063D02*
X1435827D01*
G01X1439764Y1515748D02*
Y1503937D01*
G01X1640551Y1496063D02*
X1435827D01*
G01X1559882Y277843D02*
G03X1566807Y264712I37662J11471D01*
G01X1559882Y277843D02*
G03X1539921I-9980J-3040D01*
G01X1559882D02*
G03X1566807Y264712I37662J11471D01*
G01X1559882Y277843D02*
G03X1539921I-9980J-3040D01*
G01X1532996Y264712D02*
G03X1539921Y277843I-30737J24602D01*
G01X1532996Y264712D02*
G03X1539921Y277843I-30737J24602D01*
G01X1559882Y730599D02*
G03X1566807Y717468I37662J11471D01*
G01X1559882Y730599D02*
G03X1539921I-9980J-3040D01*
G01X1559882D02*
G03X1566807Y717468I37662J11471D01*
G01X1559882Y730599D02*
G03X1539921I-9980J-3040D01*
G01X1532996Y717468D02*
G03X1539921Y730599I-30737J24601D01*
G01X1532996Y717468D02*
G03X1539921Y730599I-30737J24601D01*
G01X1559882Y1183355D02*
G03X1539921I-9980J-3040D01*
G01X1559882D02*
G03X1539921I-9980J-3040D01*
G01X1559882D02*
G03X1566807Y1170224I37662J11471D01*
G01X1559882Y1183355D02*
G03X1566807Y1170224I37662J11471D01*
G01X1532996D02*
G03X1539921Y1183355I-30737J24602D01*
G01X1532996Y1170224D02*
G03X1539921Y1183355I-30737J24601D01*
G01X1636614Y1503937D02*
X1624803D01*
G01X1636614D02*
X1624803D01*
G01D02*
G03Y1496063I0J-3937D01*
G01X1606693D02*
G03Y1503937I0J3937D01*
G01X1624803D02*
G03Y1496063I0J-3937D01*
G01X1606693D02*
G03Y1503937I0J3937D01*
G01X1636614Y1515748D02*
G03X1632677Y1519685I-3937J0D01*
G01X1636614Y1515748D02*
G03X1632677Y1519685I-3937J0D01*
G01X1648425D02*
G03X1644488Y1515748I0J-3937D01*
G01X1827756Y1519685D02*
X1648425D01*
G01D02*
G03X1644488Y1515748I0J-3937D01*
G01X1827756Y1519685D02*
X1648425D01*
G01X1636614Y1515748D02*
Y1503937D01*
G01X1640551Y1496063D02*
G03X1644488Y1500000I0J3937D01*
G01Y1515748D02*
Y1500000D01*
G01X1636614Y1515748D02*
Y1503937D01*
G01X1640551Y1496063D02*
G03X1644488Y1500000I0J3937D01*
G01Y1515748D02*
Y1500000D01*
G01X1807914Y277843D02*
G03X1814838Y264712I37663J11469D01*
G01X1807913Y277843D02*
G03X1814839Y264712I37661J11473D01*
G01X1807914Y277843D02*
G03X1787953I-9980J-3040D01*
G01X1781028Y264712D02*
G03X1787953Y277843I-30737J24602D01*
G01X1807913D02*
G03X1787953I-9980J-3040D01*
G01X1781028Y264712D02*
G03X1787953Y277843I-30737J24602D01*
G01X1781028Y264712D02*
G03X1814839I16906J-13531D01*
G01X1781028D02*
G03X1814839I16906J-13531D01*
G01X1807914Y730599D02*
G03X1814838Y717468I37663J11469D01*
G01X1807913Y730599D02*
G03X1814839Y717468I37661J11473D01*
G01X1807914Y730599D02*
G03X1787953I-9980J-3040D01*
G01X1781028Y717468D02*
G03X1787954Y730599I-30736J24604D01*
G01X1807913D02*
G03X1787953I-9980J-3040D01*
G01X1781028Y717468D02*
G03X1787953Y730599I-30737J24602D01*
G01X1781028Y717468D02*
G03X1814838I16905J-13531D01*
G01X1781028D02*
G03X1814839I16906J-13531D01*
G01X1781028Y1170224D02*
G03X1814838I16905J-13531D01*
G01X1781028D02*
G03X1814839I16906J-13531D01*
G01X1807914Y1183355D02*
G03X1814838Y1170224I37662J11468D01*
G01X1807913Y1183355D02*
G03X1814839Y1170224I37661J11473D01*
G01X1807914Y1183355D02*
G03X1787953I-9980J-3040D01*
G01X1807913D02*
G03X1787953I-9980J-3040D01*
G01X1781028Y1170224D02*
G03X1787953Y1183355I-30737J24602D01*
G01X1781028Y1170224D02*
G03X1787953Y1183355I-30737J24602D01*
G01X1869094Y1519685D02*
G03X1865157Y1515748I0J-3937D01*
G01X1919094Y1519685D02*
X1869094D01*
G01D02*
G03X1865157Y1515748I0J-3937D01*
G01X1919094Y1519685D02*
X1869094D01*
G01X1865157Y1515748D02*
Y1509055D01*
G01Y1515748D02*
Y1509055D01*
G01X1861220Y1505118D02*
X1835630D01*
G01X1861220D02*
G03X1865157Y1509055I0J3937D01*
G01X1861220Y1505118D02*
G03X1865157Y1509055I0J3937D01*
G01X1835630Y1505118D02*
X1861220D01*
G01X1831693Y1515748D02*
G03X1827756Y1519685I-3937J0D01*
G01X1831693Y1515748D02*
G03X1827756Y1519685I-3937J0D01*
G01X1831693Y1509055D02*
Y1515748D01*
G01Y1509055D02*
G03X1835630Y1505118I3937J0D01*
G01X1831693Y1509055D02*
G03X1835630Y1505118I3937J0D01*
G01X1831693Y1515748D02*
Y1509055D01*
G01X1930906Y0D02*
G03X1934843Y3937I0J3937D01*
G01X1930906Y0D02*
G03X1934843Y3937I0J3937D01*
G01D02*
Y1456693D01*
G01Y3937D02*
Y1456693D01*
G01X1930906Y1460630D02*
X1926969D01*
G01X1934843Y1456693D02*
G03X1930906Y1460630I-3937J0D01*
G01X1934843Y1456693D02*
G03X1930906Y1460630I-3937J0D01*
G01D02*
X1926969D01*
G01X1923031Y1515748D02*
G03X1919094Y1519685I-3937J0D01*
G01X1923031Y1515748D02*
G03X1919094Y1519685I-3937J0D01*
G01X1923031Y1464567D02*
Y1515748D01*
G01Y1464567D02*
G03X1926969Y1460630I3937J0D01*
G01X1923031Y1464567D02*
G03X1926969Y1460630I3937J0D01*
G01X1923031Y1515748D02*
Y1464567D01*
M02*
